# S9S_MB_2U (Grand Teton) — schematic netlist excerpt (pin names and nets, part order shuffled) for the footprints in the layout excerpt that follows; sources: Cadence DE-HDL packaged netlist, KiCad conversion of 03242023_DA0F0TMBIJ0_F0T_Motherboard_J_brd_V01_OCP.brd

PC484_P1_7  Q_CAP  3300PF 50V 10% X7R  pkg 0402  page 288 : A = SW_P12V_PVCCIN_CPU1_FLT ; B = GND
R1417  Q_RES  2K 1% CHIP  pkg 0402LF  page 219 : A = RST_PCIE_CPU0_DEV_PERST_N ; B = GND

(kicad_pcb
	(version 20260206)
	(generator "pcbnew")
	(generator_version "10.0")
	(general
		(thickness 1.6)
		(legacy_teardrops no)
	)
	(paper "A4")
	(title_block
		(title "03242023_DA0F0TMBIJ0_F0T_Motherboard_J_brd_V01_OCP.brd")
		(comment 1 "Grand Teton / footprints 1586-1587 of 6105")
	)
	(layers
		(0 "F.Cu" signal "TOP")
		(4 "In1.Cu" signal "GND")
		(6 "In2.Cu" signal "IN1")
		(8 "In3.Cu" signal "GND1")
		(10 "In4.Cu" signal "IN2")
		(12 "In5.Cu" signal "GND2")
		(14 "In6.Cu" signal "IN3")
		(16 "In7.Cu" signal "GND3")
		(18 "In8.Cu" signal "VCC")
		(20 "In9.Cu" signal "VCC1")
		(22 "In10.Cu" signal "GND4")
		(24 "In11.Cu" signal "IN4")
		(26 "In12.Cu" signal "GND5")
		(28 "In13.Cu" signal "IN5")
		(30 "In14.Cu" signal "GND6")
		(32 "In15.Cu" signal "IN6")
		(34 "In16.Cu" signal "GND7")
		(2 "B.Cu" signal "BOTTOM")
		(9 "F.Adhes" user "F.Adhesive")
		(11 "B.Adhes" user "B.Adhesive")
		(13 "F.Paste" user "Package Geometry/Pastemask Top")
		(15 "B.Paste" user "Package Geometry/Pastemask Bottom")
		(5 "F.SilkS" user "Ref Des/Silkscreen Top")
		(7 "B.SilkS" user "Ref Des/Silkscreen Bottom")
		(1 "F.Mask" user "Board Geometry/Soldermask Top")
		(3 "B.Mask" user "Board Geometry/Soldermask Bottom")
		(17 "Dwgs.User" user "User.Drawings")
		(19 "Cmts.User" user "User.Comments")
		(21 "Eco1.User" user "User.Eco1")
		(23 "Eco2.User" user "User.Eco2")
		(25 "Edge.Cuts" user "Board Geometry/Outline")
		(27 "Margin" user)
		(31 "F.CrtYd" user "Package Geometry/Place Bound Top")
		(29 "B.CrtYd" user "Package Geometry/Place Bound Bottom")
		(35 "F.Fab" user "Ref Des/Assembly Top")
		(33 "B.Fab" user "Ref Des/Assembly Bottom")
	)
	(footprint ""
		(layer "F.Cu")
		(at 85.39607 -343.496138 -90)
		(property "Reference" "PC484_P1_7"
			(at 0 0 270)
			(layer "F.SilkS")
			(hide yes)
			(effects
				(font
					(size 1.27 1.27)
				)
			)
		)
		(property "Value" ""
			(at 0 0 270)
			(layer "F.Fab")
			(effects
				(font
					(size 1.27 1.27)
				)
			)
		)
		(duplicate_pad_numbers_are_jumpers no)
		(fp_line
			(start -0.7874 0.4064)
			(end -0.7874 -0.4064)
			(stroke
				(width 0.1524)
				(type default)
			)
			(layer "F.SilkS")
		)
		(fp_line
			(start 0.7874 0.4064)
			(end -0.7874 0.4064)
			(stroke
				(width 0.1524)
				(type default)
			)
			(layer "F.SilkS")
		)
		(fp_line
			(start -0.7874 -0.4064)
			(end 0.7874 -0.4064)
			(stroke
				(width 0.1524)
				(type default)
			)
			(layer "F.SilkS")
		)
		(fp_line
			(start 0.7874 -0.4064)
			(end 0.7874 0.4064)
			(stroke
				(width 0.1524)
				(type default)
			)
			(layer "F.SilkS")
		)
		(fp_line
			(start -0.67945 0.3048)
			(end -0.67945 -0.305054)
			(stroke
				(width 0.1)
				(type default)
			)
			(layer "F.Fab")
		)
		(fp_line
			(start -0.12065 0.3048)
			(end -0.67945 0.3048)
			(stroke
				(width 0.1)
				(type default)
			)
			(layer "F.Fab")
		)
		(fp_line
			(start 0.120396 0.3048)
			(end 0.120396 0.2794)
			(stroke
				(width 0.1)
				(type default)
			)
			(layer "F.Fab")
		)
		(fp_line
			(start 0.67945 0.3048)
			(end 0.120396 0.3048)
			(stroke
				(width 0.1)
				(type default)
			)
			(layer "F.Fab")
		)
		(fp_line
			(start -0.12065 0.2794)
			(end -0.12065 0.3048)
			(stroke
				(width 0.1)
				(type default)
			)
			(layer "F.Fab")
		)
		(fp_line
			(start 0.120396 0.2794)
			(end -0.12065 0.2794)
			(stroke
				(width 0.1)
				(type default)
			)
			(layer "F.Fab")
		)
		(fp_line
			(start -0.12065 -0.2794)
			(end 0.12065 -0.2794)
			(stroke
				(width 0.1)
				(type default)
			)
			(layer "F.Fab")
		)
		(fp_line
			(start 0.12065 -0.2794)
			(end 0.12065 -0.3048)
			(stroke
				(width 0.1)
				(type default)
			)
			(layer "F.Fab")
		)
		(fp_line
			(start 0.12065 -0.3048)
			(end 0.67945 -0.3048)
			(stroke
				(width 0.1)
				(type default)
			)
			(layer "F.Fab")
		)
		(fp_line
			(start 0.67945 -0.3048)
			(end 0.67945 0.3048)
			(stroke
				(width 0.1)
				(type default)
			)
			(layer "F.Fab")
		)
		(fp_line
			(start -0.67945 -0.305054)
			(end -0.12065 -0.305054)
			(stroke
				(width 0.1)
				(type default)
			)
			(layer "F.Fab")
		)
		(fp_line
			(start -0.12065 -0.305054)
			(end -0.12065 -0.2794)
			(stroke
				(width 0.1)
				(type default)
			)
			(layer "F.Fab")
		)
		(pad "1" smd circle
			(at -0.40005 0 270)
			(size 0 0)
			(layers "F.Cu" "F.Mask" "F.Paste")
			(net "SW_P12V_PVCCIN_CPU1_FLT")
		)
		(pad "2" smd circle
			(at 0.40005 0 270)
			(size 0 0)
			(layers "F.Cu" "F.Mask" "F.Paste")
			(net "GND")
		)
	)
	(footprint ""
		(layer "F.Cu")
		(at 179.12588 -130.266948 90)
		(property "Reference" "R1417"
			(at 0 0 90)
			(layer "F.SilkS")
			(hide yes)
			(effects
				(font
					(size 1.27 1.27)
				)
			)
		)
		(property "Value" ""
			(at 0 0 90)
			(layer "F.Fab")
			(effects
				(font
					(size 1.27 1.27)
				)
			)
		)
		(duplicate_pad_numbers_are_jumpers no)
		(fp_line
			(start 0.7874 -0.4064)
			(end 0.7874 0.4064)
			(stroke
				(width 0.1524)
				(type default)
			)
			(layer "F.SilkS")
		)
		(fp_line
			(start -0.7874 -0.4064)
			(end 0.7874 -0.4064)
			(stroke
				(width 0.1524)
				(type default)
			)
			(layer "F.SilkS")
		)
		(fp_line
			(start 0.7874 0.4064)
			(end -0.7874 0.4064)
			(stroke
				(width 0.1524)
				(type default)
			)
			(layer "F.SilkS")
		)
		(fp_line
			(start -0.7874 0.4064)
			(end -0.7874 -0.4064)
			(stroke
				(width 0.1524)
				(type default)
			)
			(layer "F.SilkS")
		)
		(fp_line
			(start -0.12065 -0.305054)
			(end -0.12065 -0.2794)
			(stroke
				(width 0.1)
				(type default)
			)
			(layer "F.Fab")
		)
		(fp_line
			(start -0.67945 -0.305054)
			(end -0.12065 -0.305054)
			(stroke
				(width 0.1)
				(type default)
			)
			(layer "F.Fab")
		)
		(fp_line
			(start 0.67945 -0.3048)
			(end 0.67945 0.3048)
			(stroke
				(width 0.1)
				(type default)
			)
			(layer "F.Fab")
		)
		(fp_line
			(start 0.12065 -0.3048)
			(end 0.67945 -0.3048)
			(stroke
				(width 0.1)
				(type default)
			)
			(layer "F.Fab")
		)
		(fp_line
			(start 0.12065 -0.2794)
			(end 0.12065 -0.3048)
			(stroke
				(width 0.1)
				(type default)
			)
			(layer "F.Fab")
		)
		(fp_line
			(start -0.12065 -0.2794)
			(end 0.12065 -0.2794)
			(stroke
				(width 0.1)
				(type default)
			)
			(layer "F.Fab")
		)
		(fp_line
			(start 0.120396 0.2794)
			(end -0.12065 0.2794)
			(stroke
				(width 0.1)
				(type default)
			)
			(layer "F.Fab")
		)
		(fp_line
			(start -0.12065 0.2794)
			(end -0.12065 0.3048)
			(stroke
				(width 0.1)
				(type default)
			)
			(layer "F.Fab")
		)
		(fp_line
			(start 0.67945 0.3048)
			(end 0.120396 0.3048)
			(stroke
				(width 0.1)
				(type default)
			)
			(layer "F.Fab")
		)
		(fp_line
			(start 0.120396 0.3048)
			(end 0.120396 0.2794)
			(stroke
				(width 0.1)
				(type default)
			)
			(layer "F.Fab")
		)
		(fp_line
			(start -0.12065 0.3048)
			(end -0.67945 0.3048)
			(stroke
				(width 0.1)
				(type default)
			)
			(layer "F.Fab")
		)
		(fp_line
			(start -0.67945 0.3048)
			(end -0.67945 -0.305054)
			(stroke
				(width 0.1)
				(type default)
			)
			(layer "F.Fab")
		)
		(pad "1" smd circle
			(at -0.40005 0 90)
			(size 0 0)
			(layers "F.Cu" "F.Mask" "F.Paste")
			(net "RST_PCIE_CPU0_DEV_PERST_N")
		)
		(pad "2" smd circle
			(at 0.40005 0 90)
			(size 0 0)
			(layers "F.Cu" "F.Mask" "F.Paste")
			(net "GND")
		)
	)
)
